G04*
G04 #@! TF.GenerationSoftware,Altium Limited,Altium Designer,23.0.1 (38)*
G04*
G04 Layer_Color=0*
%FSLAX25Y25*%
%MOIN*%
G70*
G04*
G04 #@! TF.SameCoordinates,C48E81DB-6E20-4E2D-80E6-7C5AFAA1A21F*
G04*
G04*
G04 #@! TF.FilePolarity,Positive*
G04*
G01*
G75*
M02*
